# T6G (Grand Teton) — schematic netlist excerpt (pin names and nets, part order shuffled) for the footprints in the layout excerpt that follows; sources: Cadence DE-HDL packaged netlist, KiCad conversion of 04192023_DAF0TMB3IC0_F0TG_MB_C_brd_V02_OCP.brd

D88  Q_LED  IC  pkg SMLF  page 254 : A = LED_PWRGD_SYS_PWROK_R ; C = LED_PWRGD_SYS_PWROK_R_D
H98  HOLE  EMPTY  pkg TH  page 230 : \1\ = GND
PC6521  Q_CAP  22UF 16V 20% X6S  pkg C0805  page 361 : A = SW_P12V_AUX_P1V8_RETIMER_CPU1_FLT ; B = GND

(kicad_pcb
	(version 20260206)
	(generator "pcbnew")
	(generator_version "10.0")
	(general
		(thickness 1.6)
		(legacy_teardrops no)
	)
	(paper "A4")
	(title_block
		(title "04192023_DAF0TMB3IC0_F0TG_MB_C_brd_V02_OCP.brd")
		(comment 1 "Grand Teton / footprints 1285-1287 of 8354")
	)
	(layers
		(0 "F.Cu" signal "TOP")
		(4 "In1.Cu" signal "GND")
		(6 "In2.Cu" signal "IN1")
		(8 "In3.Cu" signal "GND1")
		(10 "In4.Cu" signal "IN2")
		(12 "In5.Cu" signal "GND2")
		(14 "In6.Cu" signal "IN3")
		(16 "In7.Cu" signal "GND3")
		(18 "In8.Cu" signal "VCC")
		(20 "In9.Cu" signal "VCC1")
		(22 "In10.Cu" signal "GND4")
		(24 "In11.Cu" signal "IN4")
		(26 "In12.Cu" signal "GND5")
		(28 "In13.Cu" signal "IN5")
		(30 "In14.Cu" signal "GND6")
		(32 "In15.Cu" signal "IN6")
		(34 "In16.Cu" signal "GND7")
		(2 "B.Cu" signal "BOTTOM")
		(9 "F.Adhes" user "F.Adhesive")
		(11 "B.Adhes" user "B.Adhesive")
		(13 "F.Paste" user "Package Geometry/Pastemask Top")
		(15 "B.Paste" user "Package Geometry/Pastemask Bottom")
		(5 "F.SilkS" user "Ref Des/Silkscreen Top")
		(7 "B.SilkS" user "Ref Des/Silkscreen Bottom")
		(1 "F.Mask" user "Board Geometry/Soldermask Top")
		(3 "B.Mask" user "Board Geometry/Soldermask Bottom")
		(17 "Dwgs.User" user "User.Drawings")
		(19 "Cmts.User" user "User.Comments")
		(21 "Eco1.User" user "User.Eco1")
		(23 "Eco2.User" user "User.Eco2")
		(25 "Edge.Cuts" user "Board Geometry/Outline")
		(27 "Margin" user)
		(31 "F.CrtYd" user "Package Geometry/Place Bound Top")
		(29 "B.CrtYd" user "Package Geometry/Place Bound Bottom")
		(35 "F.Fab" user "Ref Des/Assembly Top")
		(33 "B.Fab" user "Ref Des/Assembly Bottom")
	)
	(footprint ""
		(layer "F.Cu")
		(at 461.460088 -160.499806)
		(property "Reference" "H98"
			(at -3.056382 -5.99186 0)
			(unlocked yes)
			(layer "F.SilkS")
			(effects
				(font
					(size 0.7874 0.5842)
					(thickness 0.1524)
				)
				(justify left)
			)
		)
		(property "Value" ""
			(at 0 0 0)
			(layer "F.Fab")
			(effects
				(font
					(size 1.27 1.27)
				)
			)
		)
		(duplicate_pad_numbers_are_jumpers no)
		(pad "1" thru_hole circle
			(at 0 0)
			(size 10.0076 10.0076)
			(drill 5.6134)
			(layers "*.Cu" "*.Mask")
			(remove_unused_layers no)
			(net "GND")
			(clearance -1.9431)
		)
	)
	(footprint ""
		(layer "F.Cu")
		(at 233.2228 -283.5148)
		(property "Reference" "PC6521"
			(at 0 0 0)
			(layer "F.SilkS")
			(hide yes)
			(effects
				(font
					(size 1.27 1.27)
				)
			)
		)
		(property "Value" ""
			(at 0 0 0)
			(layer "F.Fab")
			(effects
				(font
					(size 1.27 1.27)
				)
			)
		)
		(duplicate_pad_numbers_are_jumpers no)
		(fp_line
			(start -1.524 -0.762)
			(end 1.524 -0.762)
			(stroke
				(width 0.1524)
				(type default)
			)
			(layer "F.SilkS")
		)
		(fp_line
			(start -1.524 0.762)
			(end -1.524 -0.762)
			(stroke
				(width 0.1524)
				(type default)
			)
			(layer "F.SilkS")
		)
		(fp_line
			(start 1.524 -0.762)
			(end 1.524 0.762)
			(stroke
				(width 0.1524)
				(type default)
			)
			(layer "F.SilkS")
		)
		(fp_line
			(start 1.524 0.762)
			(end -1.524 0.762)
			(stroke
				(width 0.1524)
				(type default)
			)
			(layer "F.SilkS")
		)
		(fp_line
			(start -1.1049 -0.724916)
			(end -1.1049 0.724916)
			(stroke
				(width 0.1)
				(type default)
			)
			(layer "F.Fab")
		)
		(fp_line
			(start -1.1049 0.724916)
			(end 1.1049 0.724916)
			(stroke
				(width 0.1)
				(type default)
			)
			(layer "F.Fab")
		)
		(fp_line
			(start 1.1049 -0.724916)
			(end -1.1049 -0.724916)
			(stroke
				(width 0.1)
				(type default)
			)
			(layer "F.Fab")
		)
		(fp_line
			(start 1.1049 0.724916)
			(end 1.1049 -0.724916)
			(stroke
				(width 0.1)
				(type default)
			)
			(layer "F.Fab")
		)
		(pad "1" smd rect
			(at -0.889 0 180)
			(size 1.016 1.27)
			(layers "F.Cu" "F.Mask" "F.Paste")
			(net "SW_P12V_AUX_P1V8_RETIMER_CPU1_FLT")
		)
		(pad "2" smd rect
			(at 0.889 0 180)
			(size 1.016 1.27)
			(layers "F.Cu" "F.Mask" "F.Paste")
			(net "GND")
		)
	)
	(footprint ""
		(layer "F.Cu")
		(at 312.443876 -70.098412 90)
		(property "Reference" "D88"
			(at -3.934714 -0.691642 90)
			(unlocked yes)
			(layer "F.SilkS")
			(effects
				(font
					(size 0.7874 0.5842)
					(thickness 0.1524)
				)
				(justify left)
			)
		)
		(property "Value" ""
			(at 0 0 90)
			(layer "F.Fab")
			(effects
				(font
					(size 1.27 1.27)
				)
			)
		)
		(duplicate_pad_numbers_are_jumpers no)
		(fp_line
			(start 1.16078 -0.4826)
			(end 1.16078 0.4826)
			(stroke
				(width 0.1524)
				(type default)
			)
			(layer "F.SilkS")
		)
		(fp_line
			(start 1.03378 -0.4826)
			(end 1.03378 0.4826)
			(stroke
				(width 0.1524)
				(type default)
			)
			(layer "F.SilkS")
		)
		(fp_line
			(start 0.90678 -0.4826)
			(end 0.90678 0.4826)
			(stroke
				(width 0.1524)
				(type default)
			)
			(layer "F.SilkS")
		)
		(fp_line
			(start -0.64008 -0.4826)
			(end 1.16078 -0.4826)
			(stroke
				(width 0.1524)
				(type default)
			)
			(layer "F.SilkS")
		)
		(fp_line
			(start -0.79248 -0.4826)
			(end 1.03378 -0.4826)
			(stroke
				(width 0.1524)
				(type default)
			)
			(layer "F.SilkS")
		)
		(fp_line
			(start -0.89408 -0.4826)
			(end 0.90678 -0.4826)
			(stroke
				(width 0.1524)
				(type default)
			)
			(layer "F.SilkS")
		)
		(fp_line
			(start 1.16078 0.4826)
			(end -0.64008 0.4826)
			(stroke
				(width 0.1524)
				(type default)
			)
			(layer "F.SilkS")
		)
		(fp_line
			(start 1.03378 0.4826)
			(end -0.79248 0.4826)
			(stroke
				(width 0.1524)
				(type default)
			)
			(layer "F.SilkS")
		)
		(fp_line
			(start 0.90678 0.4826)
			(end -0.90678 0.4826)
			(stroke
				(width 0.1524)
				(type default)
			)
			(layer "F.SilkS")
		)
		(fp_line
			(start -0.90678 0.4826)
			(end -0.90678 -0.4699)
			(stroke
				(width 0.1524)
				(type default)
			)
			(layer "F.SilkS")
		)
		(fp_line
			(start 0.499872 -0.249936)
			(end 0.499872 0.249936)
			(stroke
				(width 0.1)
				(type default)
			)
			(layer "F.Fab")
		)
		(fp_line
			(start -0.499872 -0.249936)
			(end 0.499872 -0.249936)
			(stroke
				(width 0.1)
				(type default)
			)
			(layer "F.Fab")
		)
		(fp_line
			(start 0.499872 0.249936)
			(end -0.499872 0.249936)
			(stroke
				(width 0.1)
				(type default)
			)
			(layer "F.Fab")
		)
		(fp_line
			(start -0.499872 0.249936)
			(end -0.499872 -0.249936)
			(stroke
				(width 0.1)
				(type default)
			)
			(layer "F.Fab")
		)
		(pad "A" smd rect
			(at -0.47498 0 90)
			(size 0.6096 0.7112)
			(layers "F.Cu" "F.Mask" "F.Paste")
			(net "LED_PWRGD_SYS_PWROK_R")
		)
		(pad "C" smd rect
			(at 0.47498 0 90)
			(size 0.6096 0.7112)
			(layers "F.Cu" "F.Mask" "F.Paste")
			(net "LED_PWRGD_SYS_PWROK_R_D")
		)
	)
)
